# S9S_MB_2U (Grand Teton) — schematic netlist excerpt (pin names and nets, part order shuffled) for the footprints in the layout excerpt that follows; sources: Cadence DE-HDL packaged netlist, KiCad conversion of 03242023_DA0F0TMBIJ0_F0T_Motherboard_J_brd_V01_OCP.brd

R2920  Q_RES  4.7K 5% CHIP  pkg 0402LF  page 148 : A = P3V3_AUX ; B = BIC_MONITER_ISO
R1447  Q_RES  33.2 1% CHIP  pkg 0402LF  page 222 : A = FM_CPU0_SKTOCC_LVT3_N ; B = FM_CPU0_SKTOCC_LVT3_PLD_N

(kicad_pcb
	(version 20260206)
	(generator "pcbnew")
	(generator_version "10.0")
	(general
		(thickness 1.6)
		(legacy_teardrops no)
	)
	(paper "A4")
	(title_block
		(title "03242023_DA0F0TMBIJ0_F0T_Motherboard_J_brd_V01_OCP.brd")
		(comment 1 "Grand Teton / footprints 2506-2507 of 6105")
	)
	(layers
		(0 "F.Cu" signal "TOP")
		(4 "In1.Cu" signal "GND")
		(6 "In2.Cu" signal "IN1")
		(8 "In3.Cu" signal "GND1")
		(10 "In4.Cu" signal "IN2")
		(12 "In5.Cu" signal "GND2")
		(14 "In6.Cu" signal "IN3")
		(16 "In7.Cu" signal "GND3")
		(18 "In8.Cu" signal "VCC")
		(20 "In9.Cu" signal "VCC1")
		(22 "In10.Cu" signal "GND4")
		(24 "In11.Cu" signal "IN4")
		(26 "In12.Cu" signal "GND5")
		(28 "In13.Cu" signal "IN5")
		(30 "In14.Cu" signal "GND6")
		(32 "In15.Cu" signal "IN6")
		(34 "In16.Cu" signal "GND7")
		(2 "B.Cu" signal "BOTTOM")
		(9 "F.Adhes" user "F.Adhesive")
		(11 "B.Adhes" user "B.Adhesive")
		(13 "F.Paste" user "Package Geometry/Pastemask Top")
		(15 "B.Paste" user "Package Geometry/Pastemask Bottom")
		(5 "F.SilkS" user "Ref Des/Silkscreen Top")
		(7 "B.SilkS" user "Ref Des/Silkscreen Bottom")
		(1 "F.Mask" user "Board Geometry/Soldermask Top")
		(3 "B.Mask" user "Board Geometry/Soldermask Bottom")
		(17 "Dwgs.User" user "User.Drawings")
		(19 "Cmts.User" user "User.Comments")
		(21 "Eco1.User" user "User.Eco1")
		(23 "Eco2.User" user "User.Eco2")
		(25 "Edge.Cuts" user "Board Geometry/Outline")
		(27 "Margin" user)
		(31 "F.CrtYd" user "Package Geometry/Place Bound Top")
		(29 "B.CrtYd" user "Package Geometry/Place Bound Bottom")
		(35 "F.Fab" user "Ref Des/Assembly Top")
		(33 "B.Fab" user "Ref Des/Assembly Bottom")
	)
	(footprint ""
		(layer "F.Cu")
		(at 176.58588 -130.266948 -90)
		(property "Reference" "R1447"
			(at 0 0 270)
			(layer "F.SilkS")
			(hide yes)
			(effects
				(font
					(size 1.27 1.27)
				)
			)
		)
		(property "Value" ""
			(at 0 0 270)
			(layer "F.Fab")
			(effects
				(font
					(size 1.27 1.27)
				)
			)
		)
		(duplicate_pad_numbers_are_jumpers no)
		(fp_line
			(start -0.7874 0.4064)
			(end -0.7874 -0.4064)
			(stroke
				(width 0.1524)
				(type default)
			)
			(layer "F.SilkS")
		)
		(fp_line
			(start 0.7874 0.4064)
			(end -0.7874 0.4064)
			(stroke
				(width 0.1524)
				(type default)
			)
			(layer "F.SilkS")
		)
		(fp_line
			(start -0.7874 -0.4064)
			(end 0.7874 -0.4064)
			(stroke
				(width 0.1524)
				(type default)
			)
			(layer "F.SilkS")
		)
		(fp_line
			(start 0.7874 -0.4064)
			(end 0.7874 0.4064)
			(stroke
				(width 0.1524)
				(type default)
			)
			(layer "F.SilkS")
		)
		(fp_line
			(start -0.67945 0.3048)
			(end -0.67945 -0.305054)
			(stroke
				(width 0.1)
				(type default)
			)
			(layer "F.Fab")
		)
		(fp_line
			(start -0.12065 0.3048)
			(end -0.67945 0.3048)
			(stroke
				(width 0.1)
				(type default)
			)
			(layer "F.Fab")
		)
		(fp_line
			(start 0.120396 0.3048)
			(end 0.120396 0.2794)
			(stroke
				(width 0.1)
				(type default)
			)
			(layer "F.Fab")
		)
		(fp_line
			(start 0.67945 0.3048)
			(end 0.120396 0.3048)
			(stroke
				(width 0.1)
				(type default)
			)
			(layer "F.Fab")
		)
		(fp_line
			(start -0.12065 0.2794)
			(end -0.12065 0.3048)
			(stroke
				(width 0.1)
				(type default)
			)
			(layer "F.Fab")
		)
		(fp_line
			(start 0.120396 0.2794)
			(end -0.12065 0.2794)
			(stroke
				(width 0.1)
				(type default)
			)
			(layer "F.Fab")
		)
		(fp_line
			(start -0.12065 -0.2794)
			(end 0.12065 -0.2794)
			(stroke
				(width 0.1)
				(type default)
			)
			(layer "F.Fab")
		)
		(fp_line
			(start 0.12065 -0.2794)
			(end 0.12065 -0.3048)
			(stroke
				(width 0.1)
				(type default)
			)
			(layer "F.Fab")
		)
		(fp_line
			(start 0.12065 -0.3048)
			(end 0.67945 -0.3048)
			(stroke
				(width 0.1)
				(type default)
			)
			(layer "F.Fab")
		)
		(fp_line
			(start 0.67945 -0.3048)
			(end 0.67945 0.3048)
			(stroke
				(width 0.1)
				(type default)
			)
			(layer "F.Fab")
		)
		(fp_line
			(start -0.67945 -0.305054)
			(end -0.12065 -0.305054)
			(stroke
				(width 0.1)
				(type default)
			)
			(layer "F.Fab")
		)
		(fp_line
			(start -0.12065 -0.305054)
			(end -0.12065 -0.2794)
			(stroke
				(width 0.1)
				(type default)
			)
			(layer "F.Fab")
		)
		(pad "1" smd circle
			(at -0.40005 0 270)
			(size 0 0)
			(layers "F.Cu" "F.Mask" "F.Paste")
			(net "FM_CPU0_SKTOCC_LVT3_N")
		)
		(pad "2" smd circle
			(at 0.40005 0 270)
			(size 0 0)
			(layers "F.Cu" "F.Mask" "F.Paste")
			(net "FM_CPU0_SKTOCC_LVT3_PLD_N")
		)
	)
	(footprint ""
		(layer "F.Cu")
		(at 118.849902 -409.113228 180)
		(property "Reference" "R2920"
			(at 0 0 180)
			(layer "F.SilkS")
			(hide yes)
			(effects
				(font
					(size 1.27 1.27)
				)
			)
		)
		(property "Value" ""
			(at 0 0 180)
			(layer "F.Fab")
			(effects
				(font
					(size 1.27 1.27)
				)
			)
		)
		(duplicate_pad_numbers_are_jumpers no)
		(fp_line
			(start 0.7874 0.4064)
			(end -0.7874 0.4064)
			(stroke
				(width 0.1524)
				(type default)
			)
			(layer "F.SilkS")
		)
		(fp_line
			(start 0.7874 -0.4064)
			(end 0.7874 0.4064)
			(stroke
				(width 0.1524)
				(type default)
			)
			(layer "F.SilkS")
		)
		(fp_line
			(start -0.7874 0.4064)
			(end -0.7874 -0.4064)
			(stroke
				(width 0.1524)
				(type default)
			)
			(layer "F.SilkS")
		)
		(fp_line
			(start -0.7874 -0.4064)
			(end 0.7874 -0.4064)
			(stroke
				(width 0.1524)
				(type default)
			)
			(layer "F.SilkS")
		)
		(fp_line
			(start 0.67945 0.3048)
			(end 0.120396 0.3048)
			(stroke
				(width 0.1)
				(type default)
			)
			(layer "F.Fab")
		)
		(fp_line
			(start 0.67945 -0.3048)
			(end 0.67945 0.3048)
			(stroke
				(width 0.1)
				(type default)
			)
			(layer "F.Fab")
		)
		(fp_line
			(start 0.12065 -0.2794)
			(end 0.12065 -0.3048)
			(stroke
				(width 0.1)
				(type default)
			)
			(layer "F.Fab")
		)
		(fp_line
			(start 0.12065 -0.3048)
			(end 0.67945 -0.3048)
			(stroke
				(width 0.1)
				(type default)
			)
			(layer "F.Fab")
		)
		(fp_line
			(start 0.120396 0.3048)
			(end 0.120396 0.2794)
			(stroke
				(width 0.1)
				(type default)
			)
			(layer "F.Fab")
		)
		(fp_line
			(start 0.120396 0.2794)
			(end -0.12065 0.2794)
			(stroke
				(width 0.1)
				(type default)
			)
			(layer "F.Fab")
		)
		(fp_line
			(start -0.12065 0.3048)
			(end -0.67945 0.3048)
			(stroke
				(width 0.1)
				(type default)
			)
			(layer "F.Fab")
		)
		(fp_line
			(start -0.12065 0.2794)
			(end -0.12065 0.3048)
			(stroke
				(width 0.1)
				(type default)
			)
			(layer "F.Fab")
		)
		(fp_line
			(start -0.12065 -0.2794)
			(end 0.12065 -0.2794)
			(stroke
				(width 0.1)
				(type default)
			)
			(layer "F.Fab")
		)
		(fp_line
			(start -0.12065 -0.305054)
			(end -0.12065 -0.2794)
			(stroke
				(width 0.1)
				(type default)
			)
			(layer "F.Fab")
		)
		(fp_line
			(start -0.67945 0.3048)
			(end -0.67945 -0.305054)
			(stroke
				(width 0.1)
				(type default)
			)
			(layer "F.Fab")
		)
		(fp_line
			(start -0.67945 -0.305054)
			(end -0.12065 -0.305054)
			(stroke
				(width 0.1)
				(type default)
			)
			(layer "F.Fab")
		)
		(pad "1" smd circle
			(at -0.40005 0 180)
			(size 0 0)
			(layers "F.Cu" "F.Mask" "F.Paste")
			(net "P3V3_AUX")
		)
		(pad "2" smd circle
			(at 0.40005 0 180)
			(size 0 0)
			(layers "F.Cu" "F.Mask" "F.Paste")
			(net "BIC_MONITER_ISO")
		)
	)
)
